FILE_TYPE = CONNECTIVITY;
{Allegro Design Entry HDL 17.4-2019 S026 (4007227) 1/17/2022}
"PAGE_NUMBER" = 257;
0"NC";
1"P3V3_AUX\g";
2"GND\g";
3"P3V3_AUX\g";
4"GND\g";
5"P3V3_AUX\g";
6"P3V3_AUX\g";
7"GND\g";
8"GND\g";
9"GND\g";
10"GND\g";
11"GND\g";
12"P3V3_AUX\g";
13"GND\g";
14"P3V3_AUX\g";
15"GND\g";
16"GND\g";
17"GND\g";
18"P3V3_OCP_V3_2_R\g";
19"GND\g";
20"GND\g";
21"P3V3_AUX\g";
22"P3V3_AUX\g";
23"P3V3_OCP_V3_2_R\g";
24"P3V3_AUX\g";
25"P3V3_AUX\g";
26"P3V3_AUX\g";
27"P3V3_AUX\g";
28"GND\g";
29"GND\g";
30"GND\g";
31"OCP_V3_2_P3V3_R3_PWRGD";
32"P12V_OCP_V3_2_PLD_R_PWRGD";
33"OCP_V3_2_P3V3_PWRGD";
34"HP_LVC3_OCP_V3_2_PWRGD";
35"HP_LVC3_OCP_V3_2_P12V_PWRGD_R2";
36"HP_LVC3_OCP_V3_2_PWRGD_R2";
37"RST_PERST_OCP_V3_2_BUF_N";
38"OCP_V3_2_P3V3_PLD_R_PWRGD";
39"OCP_V3_2_P3V3_PLD_PWRGD";
40"P12V_OCP_V3_2_BUF_EN_R";
41"P12V_OCP_V3_2_BUF_EN";
42"P12V_OCP_V3_2_EN_R3";
43"P12V_OCP_V3_2_EN_R";
44"OCP_V3_2_AUX_PWR_EN";
45"OCP_V3_2_AUX_PWR_EN_R2";
46"HP_LVC3_OCP_V3_2_PRSNT2_N";
47"OCP_V3_2_P3V3_PWRGD";
48"HP_LVC3_OCP_V3_2_PWRGD_R1";
49"OCP_V3_2_P3V3_R1_PWRGD";
50"FM_OCP_V3_2_AUX_PWR_R_EN";
51"RST_PERST_OCP_V3_2_R_N";
52"RST_PERST_OCP_V3_2_BUF_R_N";
53"HP_LVC3_OCP_V3_2_P12V_R_PWRGD";
54"HP_LVC3_OCP_V3_2_P12V_PWRGD";
55"OCP_V3_2_P3V3_PWRGD";
56"HP_LVC3_OCP_V3_2_P12V_PWRGD";
57"HP_LVC3_OCP_V3_2_P12V_PWRGD_R2";
58"OCP_V3_2_P3V3_PWRGD";
59"P12V_OCP_V3_2_PLD_PWRGD";
60"OCP_V3_2_P3V3_R2_PWRGD";
61"HP_LVC3_OCP_V3_2_PRSNT2";
62"RST_PERST_OCP_V3_2_N";
%"Q_RES"
"2","(-1825,-225)","2","pure_quanta","I10";
;
LOCATION"R1176"
$SEC"1"
CDS_SEC"1"
VALUE"10K"
WATTAGE"1/16W"
PACK_TYPE"0402LF"
TOLERANCE"1%"
MATERIAL"CHIP"
CDS_LIB"pure_quanta"
PART_NUMBER"CS31002FB08";
"A"
$PN"1"1;
"B"
$PN"2"50;
%"UNIVERSAL_POWER"
"1","(-1825,100)","2","pure_quanta_power","I11";
;
HDL_POWER"P3V3_AUX"
CDS_LIB"pure_quanta_power";
"A"1;
%"Q_RES"
"1","(-1275,-450)","0","pure_quanta","I12";
;
LOCATION"R1178"
$SEC"1"
CDS_SEC"1"
VALUE"33.2"
MATERIAL"CHIP"
PACK_TYPE"0402LF"
WATTAGE"1/16W"
TOLERANCE"1%"
CDS_LIB"pure_quanta"
PART_NUMBER"CS03322FB03";
"B"
$PN"2"48;
"A"
$PN"1"31;
%"UNIVERSAL_GND"
"1","(-250,-375)","0","pure_quanta_power","I13";
;
CDS_LIB"pure_quanta_power"
HDL_POWER"GND";
"A"2;
%"Q_CAP"
"1","(-250,-175)","2","pure_quanta","I14";
;
LOCATION"C1065"
$SEC"1"
CDS_SEC"1"
MATERIAL"X7R"
VALUE"0.1UF"
PACK_TYPE"0402"
VOLTAGE"25V"
TOLERANCE"10%"
CDS_LIB"pure_quanta"
PART_NUMBER"CH4104K1B00";
"B"
$PN"2"2;
"A"
$PN"1"24;
%"UNIVERSAL_POWER"
"1","(-225,50)","2","pure_quanta_power","I15";
;
HDL_POWER"P3V3_AUX"
CDS_LIB"pure_quanta_power";
"A"24;
%"Q_RES"
"1","(-1200,725)","0","pure_quanta","I16";
;
LOCATION"R1173"
$SEC"1"
CDS_SEC"1"
MATERIAL"CHIP"
PACK_TYPE"0402LF"
VALUE"33.2"
WATTAGE"1/16W"
TOLERANCE"1%"
CDS_LIB"pure_quanta"
PART_NUMBER"CS03322FB03";
"B"
$PN"2"34;
"A"
$PN"1"31;
%"Q_RES"
"1","(-1200,825)","0","pure_quanta","I17";
;
LOCATION"R1174"
$SEC"1"
CDS_SEC"1"
PACK_TYPE"0402LF"
MATERIAL"CHIP"
VALUE"33.2"
TOLERANCE"1%"
WATTAGE"1/16W"
CDS_LIB"pure_quanta"
PART_NUMBER"CS03322FB03";
"B"
$PN"2"51;
"A"
$PN"1"62;
%"Q_RES"
"1","(-1525,1575)","0","pure_quanta","I18";
;
LOCATION"R1166"
$SEC"1"
CDS_SEC"1"
PACK_TYPE"0402LF"
WATTAGE"1/16W"
TOLERANCE"5%"
VALUE"0"
MATERIAL"CHIP"
CDS_LIB"pure_quanta"
PART_NUMBER"CS00002JB13";
"B"
$PN"2"59;
"A"
$PN"1"32;
%"Q_RES"
"2","(-1075,1925)","2","pure_quanta","I19";
;
LOCATION"R1167"
$SEC"1"
CDS_SEC"1"
TOLERANCE"1%"
WATTAGE"1/16W"
PACK_TYPE"0402LF"
MATERIAL"CHIP"
VALUE"1K"
CDS_LIB"pure_quanta"
PART_NUMBER"CS21002FB06";
"A"
$PN"1"3;
"B"
$PN"2"59;
%"UNIVERSAL_POWER"
"1","(-1075,2175)","2","pure_quanta_power","I20";
;
HDL_POWER"P3V3_AUX"
CDS_LIB"pure_quanta_power";
"A"3;
%"UNIVERSAL_GND"
"1","(-4075,2525)","0","pure_quanta_power","I23";
;
CDS_LIB"pure_quanta_power"
HDL_POWER"GND";
"A"4;
%"MOSFET_N"
"1","(-4125,3075)","0","pure_quanta","I24";
;
LOCATION"U32"
$SEC"1"
CDS_SEC"1"
MATERIAL"IC"
MANUF_PN"BSS138K"
VALUE"BSS138K"
PACK_TYPE"SMLF"
CDS_LIB"pure_quanta"
CDS_LMAN_SYM_OUTLINE"-50,50,100,-150"
PART_NUMBER"BAM138K0000";
"GATE"
$PN"G"46;
"SOURCE"
$PN"S"4;
"DRAIN"
$PN"D"61;
%"Q_RES"
"2","(-4075,3625)","2","pure_quanta","I25";
;
LOCATION"R1149"
$SEC"1"
CDS_SEC"1"
TOLERANCE"1%"
VALUE"1K"
MATERIAL"CHIP"
WATTAGE"1/16W"
PACK_TYPE"0402LF"
CDS_LIB"pure_quanta"
PART_NUMBER"CS21002FB06";
"A"
$PN"1"5;
"B"
$PN"2"61;
%"UNIVERSAL_POWER"
"1","(-4075,4025)","2","pure_quanta_power","I26";
;
HDL_POWER"P3V3_AUX"
CDS_LIB"pure_quanta_power";
"A"5;
%"Q_RES"
"1","(-2325,3425)","0","pure_quanta","I28";
;
LOCATION"R1164"
$SEC"1"
CDS_SEC"1"
VALUE"0"
TOLERANCE"5%"
MATERIAL"EMPTY"
CDS_LIB"pure_quanta"
PACK_TYPE"0402LF"
WATTAGE"1/16W"
PART_NUMBER"CS00002JB13";
"B"
$PN"2"42;
"A"
$PN"1"43;
%"Q_RES"
"1","(-4000,1575)","0","pure_quanta","I3";
;
LOCATION"R1163"
$SEC"1"
CDS_SEC"1"
TOLERANCE"5%"
PACK_TYPE"0402LF"
VALUE"0"
MATERIAL"CHIP"
WATTAGE"1/16W"
CDS_LIB"pure_quanta"
PART_NUMBER"CS00002JB13";
"B"
$PN"2"53;
"A"
$PN"1"54;
%"UNIVERSAL_GND"
"1","(-1525,2950)","0","pure_quanta_power","I30";
;
CDS_LIB"pure_quanta_power"
HDL_POWER"GND";
"A"29;
%"74LVC1G08W57"
"1","(-950,3325)","0","pure_quanta","I31";
;
LOCATION"U31"
SEC"1"
PART_TYPE"SMLF"
MATERIAL"IC"
VALUE"74LVC1G08W5-7"
NEEDS_NO_SIZE"TRUE"
CDS_LMAN_SYM_OUTLINE"-150,150,150,-150"
CDS_LIB"pure_quanta"
SEC_TYPE""
PART_NUMBER"AL1G0008020";
"VCC"
$PN"5"26;
"Y"
$PN"4"41;
"GND"
$PN"3"29;
"B"
$PN"2"61;
"A"
$PN"1"42;
%"Q_RES"
"2","(-1425,3850)","2","pure_quanta","I32";
;
LOCATION"R1165"
$SEC"1"
CDS_SEC"1"
PACK_TYPE"0402LF"
VALUE"1K"
TOLERANCE"1%"
WATTAGE"1/16W"
MATERIAL"CHIP"
CDS_LIB"pure_quanta"
PART_NUMBER"CS21002FB06";
"A"
$PN"1"6;
"B"
$PN"2"42;
%"UNIVERSAL_POWER"
"1","(-1425,4250)","2","pure_quanta_power","I33";
;
HDL_POWER"P3V3_AUX"
CDS_LIB"pure_quanta_power";
"A"6;
%"Q_RES"
"1","(-650,2350)","0","pure_quanta","I34";
;
LOCATION"R1169"
$SEC"1"
CDS_SEC"1"
WATTAGE"1/16W"
MATERIAL"CHIP"
VALUE"0"
TOLERANCE"5%"
PACK_TYPE"0402LF"
CDS_LIB"pure_quanta"
PART_NUMBER"CS00002JB13";
"B"
$PN"2"60;
"A"
$PN"1"47;
%"UNIVERSAL_GND"
"1","(-350,3375)","0","pure_quanta_power","I35";
;
CDS_LIB"pure_quanta_power"
HDL_POWER"GND";
"A"7;
%"Q_CAP"
"1","(-350,3675)","0","pure_quanta","I36";
;
LOCATION"C1062"
$SEC"1"
CDS_SEC"1"
VALUE"0.1UF"
VOLTAGE"25V"
PACK_TYPE"0402"
MATERIAL"X7R"
TOLERANCE"10%"
CDS_LIB"pure_quanta"
PART_NUMBER"CH4104K1B00";
"B"
$PN"2"7;
"A"
$PN"1"26;
%"UNIVERSAL_POWER"
"1","(-350,3950)","2","pure_quanta_power","I37";
;
HDL_POWER"P3V3_AUX"
CDS_LIB"pure_quanta_power";
"A"26;
%"UNIVERSAL_GND"
"1","(-50,-775)","0","pure_quanta_power","I38";
;
CDS_LIB"pure_quanta_power"
HDL_POWER"GND";
"A"8;
%"Q_RES"
"1","(625,-1300)","2","pure_quanta","I39";
;
LOCATION"R1147"
$SEC"1"
CDS_SEC"1"
MATERIAL"EMPTY"
VALUE"0"
CDS_LIB"pure_quanta"
BOM_COST"MEM"
WATTAGE"1/16W"
TOLERANCE"5%"
PACK_TYPE"0402LF"
PART_NUMBER"CS00002JB13";
"B"
$PN"2"50;
"A"
$PN"1"45;
%"UNIVERSAL_GND"
"1","(-3300,1775)","0","pure_quanta_power","I4";
;
CDS_LIB"pure_quanta_power"
HDL_POWER"GND";
"A"9;
%"74LVC1G32GW"
"1","(225,-500)","0","pure_quanta","I40";
;
LOCATION"U37"
$SEC"1"
CDS_SEC"1"
MATERIAL"IC"
PACK_TYPE"SMLF"
VALUE"74LVC1G32GW"
CDS_LIB"pure_quanta"
NEEDS_NO_SIZE"TRUE"
PART_NUMBER"ALVC1G32007";
"GND"
$PN"3"8;
"O"
$PN"4"45;
"I1"
$PN"2"50;
"VCC"
$PN"5"24;
"I0"
$PN"1"48;
%"Q_RES"
"1","(625,200)","2","pure_quanta","I41";
;
LOCATION"R1146"
$SEC"1"
CDS_SEC"1"
MATERIAL"EMPTY"
VALUE"0"
CDS_LIB"pure_quanta"
PACK_TYPE"0402LF"
TOLERANCE"5%"
WATTAGE"1/16W"
BOM_COST"MEM"
PART_NUMBER"CS00002JB13";
"B"
$PN"2"48;
"A"
$PN"1"45;
%"Q_RES"
"1","(1625,-500)","0","pure_quanta","I42";
;
LOCATION"R1175"
$SEC"1"
CDS_SEC"1"
VALUE"33.2"
PACK_TYPE"0402LF"
MATERIAL"CHIP"
CDS_LIB"pure_quanta"
TOLERANCE"1%"
WATTAGE"1/16W"
PART_NUMBER"CS03322FB03";
"B"
$PN"2"44;
"A"
$PN"1"45;
%"UNIVERSAL_GND"
"1","(-50,350)","0","pure_quanta_power","I43";
;
CDS_LIB"pure_quanta_power"
HDL_POWER"GND";
"A"10;
%"UNIVERSAL_GND"
"1","(125,2150)","0","pure_quanta_power","I44";
;
CDS_LIB"pure_quanta_power"
HDL_POWER"GND";
"A"28;
%"SN74LVC1G07DBVR"
"1","(700,2350)","0","pure_quanta","I45";
;
LOCATION"U34"
$SEC"1"
CDS_SEC"1"
MATERIAL"IC"
VALUE"SN74LVC1G07DBVR"
PACK_TYPE"SMLF"
NEEDS_NO_SIZE"TRUE"
CDS_LIB"pure_quanta"
PART_NUMBER"AL1G0007024";
"NC"
$PN"1"0;
"Y"
$PN"4"39;
"GND"
$PN"3"28;
"A"
$PN"2"60;
"VCC"
$PN"5"27;
%"Q_CAP"
"1","(850,1000)","0","pure_quanta","I46";
;
LOCATION"C1064"
$SEC"1"
CDS_SEC"1"
VOLTAGE"25V"
VALUE"0.1UF"
TOLERANCE"10%"
MATERIAL"X7R"
PACK_TYPE"0402"
CDS_LIB"pure_quanta"
PART_NUMBER"CH4104K1B00";
"B"
$PN"2"11;
"A"
$PN"1"22;
%"UNIVERSAL_GND"
"1","(850,800)","0","pure_quanta_power","I47";
;
CDS_LIB"pure_quanta_power"
HDL_POWER"GND";
"A"11;
%"UNIVERSAL_POWER"
"1","(850,1275)","2","pure_quanta_power","I48";
;
HDL_POWER"P3V3_AUX"
CDS_LIB"pure_quanta_power";
"A"22;
%"Q_RES"
"1","(1850,675)","0","pure_quanta","I49";
;
LOCATION"R1177"
$SEC"1"
CDS_SEC"1"
MATERIAL"CHIP"
VALUE"33.2"
PACK_TYPE"0402LF"
WATTAGE"1/16W"
TOLERANCE"1%"
CDS_LIB"pure_quanta"
PART_NUMBER"CS03322FB03";
"B"
$PN"2"37;
"A"
$PN"1"52;
%"Q_CAP"
"1","(-3300,2000)","2","pure_quanta","I5";
;
LOCATION"C1061"
$SEC"1"
CDS_SEC"1"
TOLERANCE"10%"
VOLTAGE"25V"
MATERIAL"X7R"
PACK_TYPE"0402"
VALUE"0.1UF"
CDS_LIB"pure_quanta"
PART_NUMBER"CH4104K1B00";
"B"
$PN"2"9;
"A"
$PN"1"25;
%"Q_RES"
"2","(2500,-25)","0","pure_quanta","I51";
;
LOCATION"R1172"
$SEC"1"
CDS_SEC"1"
PACK_TYPE"0402LF"
VALUE"10K"
MATERIAL"EMPTY"
WATTAGE"1/16W"
TOLERANCE"5%"
CDS_LIB"pure_quanta"
PART_NUMBER"CS31002JB08";
"A"
$PN"1"12;
"B"
$PN"2"44;
%"UNIVERSAL_POWER"
"1","(2500,225)","2","pure_quanta_power","I52";
;
HDL_POWER"P3V3_AUX"
CDS_LIB"pure_quanta_power";
"A"12;
%"UNIVERSAL_GND"
"1","(-25,2550)","0","pure_quanta_power","I54";
;
CDS_LIB"pure_quanta_power"
HDL_POWER"GND";
"A"13;
%"Q_CAP"
"1","(-25,2775)","2","pure_quanta","I55";
;
LOCATION"C1063"
$SEC"1"
CDS_SEC"1"
MATERIAL"X7R"
TOLERANCE"10%"
PACK_TYPE"0402"
VOLTAGE"25V"
VALUE"0.1UF"
CDS_LIB"pure_quanta"
PART_NUMBER"CH4104K1B00";
"B"
$PN"2"13;
"A"
$PN"1"27;
%"UNIVERSAL_POWER"
"1","(0,3100)","2","pure_quanta_power","I56";
;
HDL_POWER"P3V3_AUX"
CDS_LIB"pure_quanta_power";
"A"27;
%"Q_RES"
"1","(450,3275)","0","pure_quanta","I57";
;
LOCATION"R1168"
$SEC"1"
CDS_SEC"1"
VALUE"0"
MATERIAL"CHIP"
TOLERANCE"5%"
WATTAGE"1/16W"
PACK_TYPE"0402LF"
CDS_LIB"pure_quanta"
PART_NUMBER"CS00002JB13";
"B"
$PN"2"40;
"A"
$PN"1"41;
%"Q_RES"
"1","(1775,2350)","0","pure_quanta","I58";
;
LOCATION"R1170"
$SEC"1"
CDS_SEC"1"
MATERIAL"CHIP"
VALUE"0"
WATTAGE"1/16W"
TOLERANCE"5%"
PACK_TYPE"0402LF"
CDS_LIB"pure_quanta"
PART_NUMBER"CS00002JB13";
"B"
$PN"2"38;
"A"
$PN"1"39;
%"UNIVERSAL_POWER"
"1","(-3275,2325)","2","pure_quanta_power","I6";
;
HDL_POWER"P3V3_AUX"
CDS_LIB"pure_quanta_power";
"A"25;
%"Q_RES"
"2","(2275,2700)","2","pure_quanta","I60";
;
LOCATION"R1171"
$SEC"1"
CDS_SEC"1"
PACK_TYPE"0402LF"
VALUE"1K"
TOLERANCE"1%"
MATERIAL"CHIP"
WATTAGE"1/16W"
CDS_LIB"pure_quanta"
PART_NUMBER"CS21002FB06";
"A"
$PN"1"14;
"B"
$PN"2"38;
%"UNIVERSAL_POWER"
"1","(2275,2950)","2","pure_quanta_power","I61";
;
HDL_POWER"P3V3_AUX"
CDS_LIB"pure_quanta_power";
"A"14;
%"74LVC1G08W57"
"1","(300,725)","0","pure_quanta","I63";
;
LOCATION"U35"
$SEC"1"
CDS_SEC"1"
VALUE"74LVC1G08W5-7"
MATERIAL"IC"
PART_TYPE"SMLF"
NEEDS_NO_SIZE"TRUE"
CDS_LMAN_SYM_OUTLINE"-150,150,150,-150"
CDS_LIB"pure_quanta"
PART_NUMBER"AL1G0008020";
"VCC"
$PN"5"22;
"Y"
$PN"4"52;
"GND"
$PN"3"10;
"B"
$PN"2"34;
"A"
$PN"1"51;
%"SN74LVC1G07DBVR"
"1","(-2575,1575)","0","pure_quanta","I64";
;
LOCATION"U33"
$SEC"1"
CDS_SEC"1"
VALUE"SN74LVC1G07DBVR"
MATERIAL"IC"
PACK_TYPE"SMLF"
NEEDS_NO_SIZE"TRUE"
CDS_LIB"pure_quanta"
PART_NUMBER"AL1G0007024";
"NC"
$PN"1"0;
"Y"
$PN"4"32;
"GND"
$PN"3"30;
"A"
$PN"2"53;
"VCC"
$PN"5"25;
%"UNIVERSAL_GND"
"1","(-5150,-1675)","0","pure_quanta_power","I65";
;
CDS_LIB"pure_quanta_power"
HDL_POWER"GND";
"A"15;
%"Q_CAP"
"1","(-5150,-1400)","2","pure_quanta","I66";
;
LOCATION"C8009"
$SEC"1"
CDS_SEC"1"
PACK_TYPE"0402"
TOLERANCE"10%"
MATERIAL"X7R"
VOLTAGE"25V"
VALUE"0.1UF"
CDS_LIB"pure_quanta"
PART_NUMBER"CH4104K1B00";
"B"
$PN"2"15;
"A"
$PN"1"23;
%"APX80929SAG7"
"1","(-4600,-1150)","2","pure_quanta","I67";
;
LOCATION"U8002"
SEC"1"
VALUE"APX809-29SAG-7"
PART_TYPE"SMLF"
MATERIAL"IC"
SEC_TYPE""
CDS_LIB"pure_quanta"
CDS_LMAN_SYM_OUTLINE"-225,200,225,-200"
NEEDS_NO_SIZE"TRUE"
PART_NUMBER"AL080929000";
"GND"
$PN"1"17;
"RESET_L \B"
$PN"2"49;
"VCC"
$PN"3"23;
%"UNIVERSAL_POWER"
"1","(-5150,-875)","2","pure_quanta_power","I68";
;
HDL_POWER"P3V3_OCP_V3_2_R"
CDS_LIB"pure_quanta_power";
"A"23;
%"UNIVERSAL_GND"
"1","(-3525,-1775)","0","pure_quanta_power","I69";
;
CDS_LIB"pure_quanta_power"
HDL_POWER"GND";
"A"16;
%"Q_RES"
"2","(-3525,-1525)","0","pure_quanta","I70";
;
LOCATION"R8096"
$SEC"1"
CDS_SEC"1"
PACK_TYPE"0402LF"
MATERIAL"CHIP"
WATTAGE"1/16W"
VALUE"100K"
TOLERANCE"1%"
CDS_LIB"pure_quanta"
PART_NUMBER"CS41002FB09";
"A"
$PN"1"49;
"B"
$PN"2"16;
%"UNIVERSAL_GND"
"1","(-4050,-1150)","0","pure_quanta_power","I71";
;
CDS_LIB"pure_quanta_power"
HDL_POWER"GND";
"A"17;
%"UNIVERSAL_POWER"
"1","(-3375,-725)","2","pure_quanta_power","I72";
;
HDL_POWER"P3V3_OCP_V3_2_R"
CDS_LIB"pure_quanta_power";
"A"18;
%"Q_RES"
"1","(-3050,-1250)","0","pure_quanta","I73";
;
LOCATION"R8097"
$SEC"1"
CDS_SEC"1"
WATTAGE"1/16W"
PACK_TYPE"0402LF"
VALUE"0"
TOLERANCE"5%"
MATERIAL"CHIP"
CDS_LIB"pure_quanta"
PART_NUMBER"CS00002JB13";
"B"
$PN"2"55;
"A"
$PN"1"49;
%"Q_RES"
"2","(-3375,-950)","2","pure_quanta","I77";
;
LOCATION"R8095"
$SEC"1"
CDS_SEC"1"
WATTAGE"1/16W"
VALUE"10K"
TOLERANCE"5%"
PACK_TYPE"0402LF"
MATERIAL"EMPTY"
CDS_LIB"pure_quanta"
PART_NUMBER"CS31002JB08";
"A"
$PN"1"18;
"B"
$PN"2"49;
%"74LVC1G08W57"
"1","(-4275,625)","0","pure_quanta","I78";
;
LOCATION"U9051"
$SEC"1"
CDS_SEC"1"
VALUE"74LVC1G08W5-7"
MATERIAL"IC"
PART_TYPE"SMLF"
CDS_LIB"pure_quanta"
CDS_LMAN_SYM_OUTLINE"-150,150,150,-150"
NEEDS_NO_SIZE"TRUE"
PART_NUMBER"AL1G0008020";
"VCC"
$PN"5"21;
"Y"
$PN"4"36;
"GND"
$PN"3"19;
"B"
$PN"2"57;
"A"
$PN"1"58;
%"UNIVERSAL_GND"
"1","(-4625,275)","0","pure_quanta_power","I79";
;
CDS_LIB"pure_quanta_power"
HDL_POWER"GND";
"A"19;
%"UNIVERSAL_POWER"
"1","(-3850,1275)","2","pure_quanta_power","I80";
;
HDL_POWER"P3V3_AUX"
CDS_LIB"pure_quanta_power";
"A"21;
%"Q_CAP"
"1","(-3850,975)","0","pure_quanta","I81";
;
LOCATION"C9051"
$SEC"1"
CDS_SEC"1"
MATERIAL"X7R"
VOLTAGE"25V"
TOLERANCE"10%"
PACK_TYPE"0402"
VALUE"0.1UF"
CDS_LIB"pure_quanta"
PART_NUMBER"CH4104K1B00";
"B"
$PN"2"20;
"A"
$PN"1"21;
%"UNIVERSAL_GND"
"1","(-3850,750)","0","pure_quanta_power","I82";
;
CDS_LIB"pure_quanta_power"
HDL_POWER"GND";
"A"20;
%"Q_RES"
"1","(-4325,75)","0","pure_quanta","I84";
;
LOCATION"R1523"
$SEC"1"
CDS_SEC"1"
WATTAGE"1/16W"
PACK_TYPE"0402LF"
VALUE"0"
TOLERANCE"5%"
MATERIAL"CHIP"
CDS_LIB"pure_quanta"
PART_NUMBER"CS00002JB13";
"B"
$PN"2"35;
"A"
$PN"1"56;
%"Q_RES"
"1","(-2300,725)","0","pure_quanta","I88";
;
LOCATION"R1525"
$SEC"1"
CDS_SEC"1"
MATERIAL"EMPTY"
VALUE"0"
TOLERANCE"5%"
PACK_TYPE"0402LF"
WATTAGE"1/16W"
CDS_LIB"pure_quanta"
PART_NUMBER"CS00002JB13";
"B"
$PN"2"31;
"A"
$PN"1"33;
%"Q_RES"
"1","(-2875,575)","0","pure_quanta","I89";
;
LOCATION"R1524"
$SEC"1"
CDS_SEC"1"
TOLERANCE"5%"
VALUE"0"
WATTAGE"1/16W"
MATERIAL"CHIP"
PACK_TYPE"0402LF"
CDS_LIB"pure_quanta"
PART_NUMBER"CS00002JB13";
"B"
$PN"2"31;
"A"
$PN"1"36;
%"UNIVERSAL_GND"
"1","(-3150,1375)","0","pure_quanta_power","I9";
;
CDS_LIB"pure_quanta_power"
HDL_POWER"GND";
"A"30;
END.
